(kicad_pcb
	(version 20241229)
	(generator "pcbnew")
	(generator_version "9.0")
	(general
		(thickness 1.711)
		(legacy_teardrops no)
	)
	(paper "A4")
	(title_block
		(title "Antmicro Baseboard for Jetson AGX Thor")
		(date "2026-02-18")
		(rev "1.1.0")
		(company "Antmicro Ltd")
		(comment 1 "www.antmicro.com")
		(comment 9 "footprints 167-168 of 1170")
	)
	(layers
		(0 "F.Cu" signal)
		(4 "In1.Cu" signal)
		(6 "In2.Cu" signal)
		(8 "In3.Cu" signal)
		(10 "In4.Cu" jumper)
		(12 "In5.Cu" signal)
		(14 "In6.Cu" signal)
		(16 "In7.Cu" signal)
		(18 "In8.Cu" signal)
		(2 "B.Cu" signal)
		(9 "F.Adhes" user "F.Adhesive")
		(11 "B.Adhes" user "B.Adhesive")
		(13 "F.Paste" user)
		(15 "B.Paste" user)
		(5 "F.SilkS" user "F.Silkscreen")
		(7 "B.SilkS" user "B.Silkscreen")
		(1 "F.Mask" user)
		(3 "B.Mask" user)
		(17 "Dwgs.User" user "User.Drawings")
		(19 "Cmts.User" user "User.Comments")
		(21 "Eco1.User" user "User.Eco1")
		(23 "Eco2.User" user "User.Eco2")
		(25 "Edge.Cuts" user)
		(27 "Margin" user)
		(31 "F.CrtYd" user "F.Courtyard")
		(29 "B.CrtYd" user "B.Courtyard")
		(35 "F.Fab" user)
		(33 "B.Fab" user)
	)
	(footprint "antmicro-footprints:MLP44-24L_4x4x0.75mm"
		(layer "F.Cu")
		(at 181 143)
		(property "Reference" "U8"
			(at -2.7 2.8 90)
			(layer "F.SilkS")
			(effects
				(font
					(size 0.7 0.7)
					(thickness 0.15)
				)
				(justify left bottom)
			)
		)
		(property "Value" "SIC437AED-T1-GE3"
			(at -2.7 3.6 0)
			(layer "F.Fab")
			(effects
				(font
					(size 0.7 0.7)
					(thickness 0.15)
				)
				(justify left bottom)
			)
		)
		(property "Datasheet" "https://www.vishay.com/docs/75921/sic437.pdf"
			(at 0 0 0)
			(layer "F.Fab")
			(hide yes)
			(effects
				(font
					(size 1.27 1.27)
					(thickness 0.15)
				)
			)
		)
		(property "Description" "DC/DC Buck Step Down Regulator Adjustable, 4.5-28V In, 0.6V to 20V/12A Out, 1MHz, PowerPAK MLP44-24"
			(at 0 0 0)
			(layer "F.Fab")
			(hide yes)
			(effects
				(font
					(size 1.27 1.27)
					(thickness 0.15)
				)
			)
		)
		(property "Manufacturer" "Vishay"
			(at 0 0 180)
			(unlocked yes)
			(layer "F.Fab")
			(hide yes)
			(effects
				(font
					(size 1 1)
					(thickness 0.15)
				)
			)
		)
		(property "MPN" "SIC437AED-T1-GE3"
			(at 0 0 180)
			(unlocked yes)
			(layer "F.Fab")
			(hide yes)
			(effects
				(font
					(size 1 1)
					(thickness 0.15)
				)
			)
		)
		(property "Author" "Antmicro"
			(at 0 0 180)
			(unlocked yes)
			(layer "F.Fab")
			(hide yes)
			(effects
				(font
					(size 1 1)
					(thickness 0.15)
				)
			)
		)
		(property "License" "Apache-2.0"
			(at 0 0 180)
			(unlocked yes)
			(layer "F.Fab")
			(hide yes)
			(effects
				(font
					(size 1 1)
					(thickness 0.15)
				)
			)
		)
		(sheetname "/DCDC/")
		(sheetfile "dcdc.kicad_sch")
		(attr smd)
		(net_tie_pad_groups "1,2,26" "3,4,27" "5,6,7,8,9")
		(fp_line
			(start -2.11 -1.38)
			(end -2.11 -2.1)
			(stroke
				(width 0.15)
				(type solid)
			)
			(layer "F.SilkS")
		)
		(fp_line
			(start -2.11 2.11)
			(end -2.11 1.39)
			(stroke
				(width 0.15)
				(type solid)
			)
			(layer "F.SilkS")
		)
		(fp_line
			(start -1.89 -2.1)
			(end -2.11 -2.1)
			(stroke
				(width 0.15)
				(type solid)
			)
			(layer "F.SilkS")
		)
		(fp_line
			(start -1.89 2.11)
			(end -2.11 2.11)
			(stroke
				(width 0.15)
				(type solid)
			)
			(layer "F.SilkS")
		)
		(fp_line
			(start 1.44 2.11)
			(end 2.11 2.11)
			(stroke
				(width 0.15)
				(type solid)
			)
			(layer "F.SilkS")
		)
		(fp_line
			(start 1.89 -2.11)
			(end 2.11 -2.11)
			(stroke
				(width 0.15)
				(type solid)
			)
			(layer "F.SilkS")
		)
		(fp_line
			(start 2.11 -2.11)
			(end 2.11 -1.69)
			(stroke
				(width 0.15)
				(type solid)
			)
			(layer "F.SilkS")
		)
		(fp_line
			(start 2.11 2.11)
			(end 2.11 1.84)
			(stroke
				(width 0.15)
				(type solid)
			)
			(layer "F.SilkS")
		)
		(fp_circle
			(center -2.25 -1.15)
			(end -2.2 -1.15)
			(stroke
				(width 0.15)
				(type solid)
			)
			(fill yes)
			(layer "F.SilkS")
		)
		(fp_line
			(start -2.55 -2.55)
			(end 2.55 -2.55)
			(stroke
				(width 0.05)
				(type solid)
			)
			(layer "F.CrtYd")
		)
		(fp_line
			(start -2.55 2.55)
			(end -2.55 -2.55)
			(stroke
				(width 0.05)
				(type solid)
			)
			(layer "F.CrtYd")
		)
		(fp_line
			(start 2.55 -2.55)
			(end 2.55 2.55)
			(stroke
				(width 0.05)
				(type solid)
			)
			(layer "F.CrtYd")
		)
		(fp_line
			(start 2.55 2.55)
			(end -2.55 2.55)
			(stroke
				(width 0.05)
				(type solid)
			)
			(layer "F.CrtYd")
		)
		(fp_line
			(start -2 -1)
			(end -2 2)
			(stroke
				(width 0.15)
				(type solid)
			)
			(layer "F.Fab")
		)
		(fp_line
			(start -2 2)
			(end 2 2)
			(stroke
				(width 0.15)
				(type solid)
			)
			(layer "F.Fab")
		)
		(fp_line
			(start -1 -2)
			(end -2 -1)
			(stroke
				(width 0.15)
				(type solid)
			)
			(layer "F.Fab")
		)
		(fp_line
			(start 2 -2)
			(end -1 -2)
			(stroke
				(width 0.15)
				(type solid)
			)
			(layer "F.Fab")
		)
		(fp_line
			(start 2 2)
			(end 2 -2)
			(stroke
				(width 0.15)
				(type solid)
			)
			(layer "F.Fab")
		)
		(fp_text user "License: Apache-2.0"
			(at -2.7 5.6 0)
			(layer "F.Fab")
			(effects
				(font
					(size 0.7 0.7)
					(thickness 0.15)
				)
				(justify left bottom)
			)
		)
		(fp_text user "${REFERENCE}"
			(at -2.7 6.8 0)
			(layer "F.Fab")
			(effects
				(font
					(size 0.7 0.7)
					(thickness 0.15)
				)
				(justify left bottom)
			)
		)
		(fp_text user "Author: Antmicro"
			(at -2.7 8 0)
			(layer "F.Fab")
			(effects
				(font
					(size 0.7 0.7)
					(thickness 0.15)
				)
				(justify left bottom)
			)
		)
		(pad "1" smd roundrect
			(at -1.94 -0.825 90)
			(size 0.3 0.725)
			(layers "F.Cu" "F.Mask" "F.Paste")
			(roundrect_rratio 0.25)
			(net 13 "VCC")
			(pinfunction "V_{IN}")
			(pintype "power_in")
		)
		(pad "2" smd roundrect
			(at -1.94 -0.375 90)
			(size 0.3 0.725)
			(layers "F.Cu" "F.Mask" "F.Paste")
			(roundrect_rratio 0.25)
			(net 13 "VCC")
			(pinfunction "V_{IN}")
			(pintype "passive")
		)
		(pad "3" smd roundrect
			(at -1.94 0.525 90)
			(size 0.3 0.725)
			(layers "F.Cu" "F.Mask" "F.Paste")
			(roundrect_rratio 0.25)
			(net 1 "GND")
			(pinfunction "P_{GND}")
			(pintype "passive")
		)
		(pad "4" smd roundrect
			(at -1.94 0.975 90)
			(size 0.3 0.725)
			(layers "F.Cu" "F.Mask" "F.Paste")
			(roundrect_rratio 0.25)
			(net 1 "GND")
			(pinfunction "P_{GND}")
			(pintype "passive")
		)
		(pad "5" smd custom
			(at -1.475 1.94)
			(size 0.3 0.3)
			(layers "F.Cu" "F.Mask" "F.Paste")
			(net 1186 "/DCDC/12V_SW")
			(pinfunction "SW")
			(pintype "passive")
			(options
				(clearance outline)
				(anchor circle)
			)
			(primitives
				(gr_poly
					(pts
						(xy -0.15 -0.2875) (xy -0.144291 -0.316201) (xy -0.128033 -0.340533) (xy -0.103701 -0.356791)
						(xy -0.075 -0.3625) (xy 0.075 -0.3625) (xy 0.103701 -0.356791) (xy 0.128033 -0.340533) (xy 0.144291 -0.316201)
						(xy 0.15 -0.2875) (xy 0.15 0.2875) (xy 0.144291 0.316201) (xy 0.128033 0.340533) (xy 0.103701 0.356791)
						(xy 0.075 0.3625) (xy -0.075 0.3625) (xy -0.103701 0.356791) (xy -0.128033 0.340533) (xy -0.144291 0.316201)
						(xy -0.15 0.2875)
					)
					(width 0)
					(fill yes)
				)
				(gr_poly
					(pts
						(xy -0.15 -0.3625) (xy 2.2 -0.3625) (xy 2.2 -0.0875) (xy -0.15 -0.0875)
					)
					(width 0)
					(fill yes)
				)
			)
		)
		(pad "6" smd roundrect
			(at -1.025 1.94)
			(size 0.3 0.725)
			(layers "F.Cu" "F.Mask" "F.Paste")
			(roundrect_rratio 0.25)
			(net 1186 "/DCDC/12V_SW")
			(pinfunction "SW")
			(pintype "passive")
		)
		(pad "7" smd roundrect
			(at -0.575 1.94)
			(size 0.3 0.725)
			(layers "F.Cu" "F.Mask" "F.Paste")
			(roundrect_rratio 0.25)
			(net 1186 "/DCDC/12V_SW")
			(pinfunction "SW")
			(pintype "passive")
		)
		(pad "8" smd roundrect
			(at 0.125 1.94)
			(size 0.3 0.725)
			(layers "F.Cu" "F.Mask" "F.Paste")
			(roundrect_rratio 0.25)
			(net 1186 "/DCDC/12V_SW")
			(pinfunction "SW")
			(pintype "passive")
		)
		(pad "9" smd roundrect
			(at 0.575 1.94)
			(size 0.3 0.725)
			(layers "F.Cu" "F.Mask" "F.Paste")
			(roundrect_rratio 0.25)
			(net 1186 "/DCDC/12V_SW")
			(pinfunction "SW")
			(pintype "passive")
		)
		(pad "10" smd roundrect
			(at 1.025 1.935)
			(size 0.3 0.725)
			(layers "F.Cu" "F.Mask" "F.Paste")
			(roundrect_rratio 0.25)
			(net 1169 "unconnected-(U8-GL-Pad10)")
			(pinfunction "GL")
			(pintype "passive+no_connect")
		)
		(pad "11" smd roundrect
			(at 1.94 1.425 90)
			(size 0.3 0.725)
			(layers "F.Cu" "F.Mask" "F.Paste")
			(roundrect_rratio 0.25)
			(net 1170 "unconnected-(U8-GL-Pad10)_1")
			(pinfunction "GL")
			(pintype "passive+no_connect")
		)
		(pad "12" smd roundrect
			(at 1.94 0.975 90)
			(size 0.3 0.725)
			(layers "F.Cu" "F.Mask" "F.Paste")
			(roundrect_rratio 0.25)
			(net 578 "/DCDC/12V_VDRV")
			(pinfunction "V_{DRV}")
			(pintype "passive")
		)
		(pad "13" smd roundrect
			(at 1.94 0.525 90)
			(size 0.3 0.725)
			(layers "F.Cu" "F.Mask" "F.Paste")
			(roundrect_rratio 0.25)
			(net 1 "GND")
			(pinfunction "P_{GND}")
			(pintype "power_in")
		)
		(pad "14" smd roundrect
			(at 1.94 0.075 90)
			(size 0.3 0.725)
			(layers "F.Cu" "F.Mask" "F.Paste")
			(roundrect_rratio 0.25)
			(net 1172 "unconnected-(U8-P_{GOOD}-Pad14)")
			(pinfunction "P_{GOOD}")
			(pintype "output+no_connect")
		)
		(pad "15" smd roundrect
			(at 1.94 -0.375 90)
			(size 0.3 0.725)
			(layers "F.Cu" "F.Mask" "F.Paste")
			(roundrect_rratio 0.25)
			(net 20 "/DCDC/12V_VDD")
			(pinfunction "V_{DD}")
			(pintype "passive")
		)
		(pad "16" smd roundrect
			(at 1.94 -0.825 90)
			(size 0.3 0.725)
			(layers "F.Cu" "F.Mask" "F.Paste")
			(roundrect_rratio 0.25)
			(net 1 "GND")
			(pinfunction "A_{GND}")
			(pintype "power_in")
		)
		(pad "17" smd roundrect
			(at 1.94 -1.275 90)
			(size 0.3 0.725)
			(layers "F.Cu" "F.Mask" "F.Paste")
			(roundrect_rratio 0.25)
			(net 1206 "/DCDC/12V_FB")
			(pinfunction "FB")
			(pintype "passive")
		)
		(pad "18" smd roundrect
			(at 1.475 -1.94)
			(size 0.3 0.725)
			(layers "F.Cu" "F.Mask" "F.Paste")
			(roundrect_rratio 0.25)
			(net 880 "/DCDC/12V_OUT")
			(pinfunction "V_{OUT}")
			(pintype "passive")
		)
		(pad "19" smd roundrect
			(at 1.025 -1.94)
			(size 0.3 0.725)
			(layers "F.Cu" "F.Mask" "F.Paste")
			(roundrect_rratio 0.25)
			(net 1293 "/DCDC/CARRIER_PWR_ON")
			(pinfunction "EN")
			(pintype "input")
		)
		(pad "20" smd roundrect
			(at 0.575 -1.94)
			(size 0.3 0.725)
			(layers "F.Cu" "F.Mask" "F.Paste")
			(roundrect_rratio 0.25)
			(net 1205 "/DCDC/12V_MODE2")
			(pinfunction "MODE2")
			(pintype "input")
		)
		(pad "21" smd roundrect
			(at 0.125 -1.94)
			(size 0.3 0.725)
			(layers "F.Cu" "F.Mask" "F.Paste")
			(roundrect_rratio 0.25)
			(net 1204 "/DCDC/12V_MODE1")
			(pinfunction "MODE1")
			(pintype "input")
		)
		(pad "22" smd roundrect
			(at -0.575 -1.94)
			(size 0.3 0.725)
			(layers "F.Cu" "F.Mask" "F.Paste")
			(roundrect_rratio 0.25)
			(net 13 "VCC")
			(pinfunction "V_{IN}")
			(pintype "passive")
		)
		(pad "23" smd roundrect
			(at -1.025 -1.94)
			(size 0.3 0.725)
			(layers "F.Cu" "F.Mask" "F.Paste")
			(roundrect_rratio 0.25)
			(net 585 "/DCDC/12V_BOOT")
			(pinfunction "BOOT")
			(pintype "passive")
		)
		(pad "24" smd roundrect
			(at -1.475 -1.94)
			(size 0.3 0.725)
			(layers "F.Cu" "F.Mask" "F.Paste")
			(roundrect_rratio 0.25)
			(net 879 "/DCDC/12V_PHASE")
			(pinfunction "PHASE")
			(pintype "passive")
		)
		(pad "25" smd rect
			(at 0.49 -0.75 180)
			(size 1.575 1.05)
			(layers "F.Cu" "F.Mask" "F.Paste")
			(net 1 "GND")
			(pinfunction "A_{GND}")
			(pintype "passive")
		)
		(pad "26" smd rect
			(at -1.175 -0.75 180)
			(size 1.15 1.05)
			(layers "F.Cu" "F.Mask" "F.Paste")
			(net 13 "VCC")
			(pinfunction "V_{IN}")
			(pintype "passive")
		)
		(pad "27" smd custom
			(at -0.75 0.775)
			(size 1 1)
			(layers "F.Cu" "F.Mask" "F.Paste")
			(net 1 "GND")
			(pinfunction "P_{GND}")
			(pintype "passive")
			(options
				(clearance outline)
				(anchor rect)
			)
			(primitives
				(gr_poly
					(pts
						(xy -1 0.5) (xy -1 -0.7) (xy 1.825 -0.7) (xy 1.825 -0.245) (xy 1.175 -0.245) (xy 1.175 0.5)
					)
					(width 0)
					(fill yes)
				)
			)
		)
		(pad "28" smd rect
			(at 0.985 0.99 180)
			(size 0.58 0.38)
			(layers "F.Cu" "F.Mask" "F.Paste")
			(net 1171 "unconnected-(U8-GL-Pad10)_2")
			(pinfunction "GL")
			(pintype "passive+no_connect")
		)
	)
	(footprint "antmicro-footprints:C_0805_2012Metric"
		(layer "F.Cu")
		(at 170.725 126.92 90)
		(descr "Capacitor SMD 0805")
		(tags "capacitor SMD 0805")
		(property "Reference" "C268"
			(at 1.52 -4.025 90)
			(layer "F.SilkS")
			(effects
				(font
					(size 0.7 0.7)
					(thickness 0.15)
				)
				(justify left bottom)
			)
		)
		(property "Value" "C_22u_25V_0805"
			(at -2.055717 1.963152 90)
			(layer "F.Fab")
			(effects
				(font
					(size 0.7 0.7)
					(thickness 0.15)
				)
				(justify left bottom)
			)
		)
		(property "Datasheet" "https://product.samsungsem.com/mlcc/CL21A226MAYNNN.do"
			(at 0 0 90)
			(layer "F.Fab")
			(hide yes)
			(effects
				(font
					(size 1.27 1.27)
					(thickness 0.15)
				)
			)
		)
		(property "Description" "SMT Multilayer Ceramic Capacitor, 22uF, +/-20%, 25V, X5R, 0805 [2012 Metric]"
			(at 0 0 90)
			(layer "F.Fab")
			(hide yes)
			(effects
				(font
					(size 1.27 1.27)
					(thickness 0.15)
				)
			)
		)
		(property "MPN" "CL21A226MAYNNNE"
			(at 0 0 90)
			(unlocked yes)
			(layer "F.Fab")
			(hide yes)
			(effects
				(font
					(size 1 1)
					(thickness 0.15)
				)
			)
		)
		(property "Manufacturer" "Samsung Electro-Mechanics"
			(at 0 0 90)
			(unlocked yes)
			(layer "F.Fab")
			(hide yes)
			(effects
				(font
					(size 1 1)
					(thickness 0.15)
				)
			)
		)
		(property "License" "Apache-2.0"
			(at 0 0 90)
			(unlocked yes)
			(layer "F.Fab")
			(hide yes)
			(effects
				(font
					(size 1 1)
					(thickness 0.15)
				)
			)
		)
		(property "Author" "Antmicro"
			(at 0 0 90)
			(unlocked yes)
			(layer "F.Fab")
			(hide yes)
			(effects
				(font
					(size 1 1)
					(thickness 0.15)
				)
			)
		)
		(property "Val" "22u"
			(at 0 0 90)
			(unlocked yes)
			(layer "F.Fab")
			(hide yes)
			(effects
				(font
					(size 1 1)
					(thickness 0.15)
				)
			)
		)
		(property "Voltage" "25V"
			(at 0 0 90)
			(unlocked yes)
			(layer "F.Fab")
			(hide yes)
			(effects
				(font
					(size 1 1)
					(thickness 0.15)
				)
			)
		)
		(property "Dielectric" "X5R"
			(at 0 0 90)
			(unlocked yes)
			(layer "F.Fab")
			(hide yes)
			(effects
				(font
					(size 1 1)
					(thickness 0.15)
				)
			)
		)
		(property "Public" "False"
			(at 0 0 90)
			(unlocked yes)
			(layer "F.Fab")
			(hide yes)
			(effects
				(font
					(size 1 1)
					(thickness 0.15)
				)
			)
		)
		(sheetname "/DCDC/")
		(sheetfile "dcdc.kicad_sch")
		(attr smd)
		(fp_line
			(start -0.3 -0.7)
			(end 0.3 -0.7)
			(stroke
				(width 0.15)
				(type solid)
			)
			(layer "F.SilkS")
		)
		(fp_line
			(start -0.3 0.7)
			(end 0.3 0.7)
			(stroke
				(width 0.15)
				(type solid)
			)
			(layer "F.SilkS")
		)
		(fp_rect
			(start 1.95 -0.9)
			(end -1.95 0.9)
			(stroke
				(width 0.05)
				(type default)
			)
			(fill no)
			(layer "F.CrtYd")
		)
		(fp_rect
			(start -0.95 -0.675)
			(end 0.95 0.675)
			(stroke
				(width 0.15)
				(type solid)
			)
			(fill no)
			(layer "F.Fab")
		)
		(fp_text user "Author: Antmicro"
			(at -1.9 5.947 90)
			(layer "F.Fab")
			(effects
				(font
					(size 0.7 0.7)
					(thickness 0.15)
				)
				(justify left bottom)
			)
		)
		(fp_text user "${REFERENCE}"
			(at -1.9 3.947 90)
			(layer "F.Fab")
			(effects
				(font
					(size 0.7 0.7)
					(thickness 0.15)
				)
				(justify left bottom)
			)
		)
		(fp_text user "License: Apache-2.0"
			(at -1.9 4.947 90)
			(layer "F.Fab")
			(effects
				(font
					(size 0.7 0.7)
					(thickness 0.15)
				)
				(justify left bottom)
			)
		)
		(pad "1" smd roundrect
			(at -1.1 0 90)
			(size 1.2 1.3)
			(layers "F.Cu" "F.Mask" "F.Paste")
			(roundrect_rratio 0.25)
			(net 1 "GND")
			(pintype "passive")
		)
		(pad "2" smd roundrect
			(at 1.1 0 90)
			(size 1.2 1.3)
			(layers "F.Cu" "F.Mask" "F.Paste")
			(roundrect_rratio 0.25)
			(net 13 "VCC")
			(pintype "passive")
		)
	)
)
